# S9S_MB_2U (Grand Teton) — schematic netlist excerpt (pin names and nets, part order shuffled) for the footprints in the layout excerpt that follows; sources: Cadence DE-HDL packaged netlist, KiCad conversion of 03242023_DA0F0TMBIJ0_F0T_Motherboard_J_brd_V01_OCP.brd

J23  SCONN288_ADR50017P130CC  SCONN288_ADR50017-P130CC IO  pkg DDR288S_1-1VXB  page 104
  VIN_BULK0  = P12V_S3_AUX_CPU1_NVDIMM
  RFU0  = TP_CHD_CPU1_DIMM1_FRU_0
  VIN_MGMT  = P3V3_AUX
  HSCL  = I3C_SPD_DDRABCD_CPU1_LVC1_SCL_6
  HSDA  = I3C_SPD_DDRABCD_CPU1_LVC1_SDA
  VSS0  = GND
  DQ0_A  = M_D_CPU1_SA_DQ<0>
  VSS1  = GND
  DQ1_A  = M_D_CPU1_SA_DQ<1>
  VSS2  = GND
  DQS0_A_T  = M_D_CPU1_SA_DQS_DP<0>
  DQS0_A_C  = M_D_CPU1_SA_DQS_DN<0>
  VSS3  = GND
  DQ4_A  = M_D_CPU1_SA_DQ<4>
  VSS4  = GND
  DQ5_A  = M_D_CPU1_SA_DQ<5>
  VSS5  = GND
  DQ8_A  = M_D_CPU1_SA_DQ<8>
  VSS6  = GND
  DQ9_A  = M_D_CPU1_SA_DQ<9>
  VSS7  = GND
  DQS1_A_T  = M_D_CPU1_SA_DQS_DP<1>
  DQS1_A_C  = M_D_CPU1_SA_DQS_DN<1>
  VSS8  = GND
  DQ12_A  = M_D_CPU1_SA_DQ<12>
  VSS9  = GND
  DQ13_A  = M_D_CPU1_SA_DQ<13>
  VSS10  = GND
  DQ16_A  = M_D_CPU1_SA_DQ<16>
  VSS11  = GND
  DQ17_A  = M_D_CPU1_SA_DQ<17>
  VSS12  = GND
  DQS2_A_T  = M_D_CPU1_SA_DQS_DP<2>
  DQS2_A_C  = M_D_CPU1_SA_DQS_DN<2>
  VSS13  = GND
  DQ20_A  = M_D_CPU1_SA_DQ<20>
  VSS14  = GND
  DQ21_A  = M_D_CPU1_SA_DQ<21>
  VSS15  = GND
  DQ24_A  = M_D_CPU1_SA_DQ<24>
  VSS16  = GND
  DQ25_A  = M_D_CPU1_SA_DQ<25>
  VSS17  = GND
  DQS3_A_T  = M_D_CPU1_SA_DQS_DP<3>
  DQS3_A_C  = M_D_CPU1_SA_DQS_DN<3>
  VSS18  = GND
  DQ28_A  = M_D_CPU1_SA_DQ<28>
  VSS19  = GND
  DQ29_A  = M_D_CPU1_SA_DQ<29>
  VSS20  = GND
  CB0_A  = M_D_CPU1_SA_CB<0>
  VSS21  = GND
  CB1_A  = M_D_CPU1_SA_CB<1>
  VSS22  = GND
  DQS4_A_T  = M_D_CPU1_SA_DQS_DP<4>
  DQS4_A_C  = M_D_CPU1_SA_DQS_DN<4>
  VSS23  = GND
  CB4_A  = M_D_CPU1_SA_CB<4>
  VSS24  = GND
  CB5_A  = M_D_CPU1_SA_CB<5>
  VSS25  = GND
  ALERT_N  = M_D_CPU1_ALERT_N
  VSS26  = GND
  CS0_A_N  = M_D_CPU1_SA_CS_N<0>
  VSS27  = GND
  CA0_A  = M_D_CPU1_SA_CA<0>
  VSS28  = GND
  CA2_A  = M_D_CPU1_SA_CA<2>
  VSS29  = GND
  CA4_A  = M_D_CPU1_SA_CA<4>
  VSS30  = GND
  CA6_A  = M_D_CPU1_SA_CA<6>
  VSS31  = GND
  PAR_A  = M_D_CPU1_SA_PAR
  VSS32  = GND
  CA0_B  = M_D_CPU1_SB_CA<0>
  VSS33  = GND
  CA2_B  = M_D_CPU1_SB_CA<2>
  VSS34  = GND
  CA4_B  = M_D_CPU1_SB_CA<4>
  VSS35  = GND
  CA6_B  = M_D_CPU1_SB_CA<6>
  VSS36  = GND
  CS0_B_N  = M_D_CPU1_SB_CS_N<0>
  VSS37  = GND
  \lbd||rsp_a_n\  = M_D_CPU1_SA_RSP<0>
  \lbs||rsp_b_n\  = M_D_CPU1_SB_RSP<0>
  VSS38  = GND
  CB4_B  = M_D_CPU1_SB_CB<4>
  VSS39  = GND
  CB5_B  = M_D_CPU1_SB_CB<5>
  VSS40  = GND
  \dqs9_b_t||tdqs9_b_t||dbi4_b_n\  = M_D_CPU1_SB_DQS_DP<9>
  \dqs9_b_c||tdqs9_b_c\  = M_D_CPU1_SB_DQS_DN<9>
  VSS41  = GND
  CB0_B  = M_D_CPU1_SB_CB<0>
  VSS42  = GND
  CB1_B  = M_D_CPU1_SB_CB<1>
  VSS43  = GND
  DQ0_B  = M_D_CPU1_SB_DQ<0>
  VSS44  = GND
  DQ1_B  = M_D_CPU1_SB_DQ<1>
  VSS45  = GND
  DQS0_B_T  = M_D_CPU1_SB_DQS_DP<0>
  DQS0_B_C  = M_D_CPU1_SB_DQS_DN<0>
  VSS46  = GND
  DQ4_B  = M_D_CPU1_SB_DQ<4>
  VSS47  = GND
  DQ5_B  = M_D_CPU1_SB_DQ<5>
  VSS48  = GND
  DQ8_B  = M_D_CPU1_SB_DQ<8>
  VSS49  = GND
  DQ9_B  = M_D_CPU1_SB_DQ<9>
  VSS50  = GND
  DQS1_B_T  = M_D_CPU1_SB_DQS_DP<1>
  DQS1_B_C  = M_D_CPU1_SB_DQS_DN<1>
  VSS51  = GND
  DQ12_B  = M_D_CPU1_SB_DQ<12>
  VSS52  = GND
  DQ13_B  = M_D_CPU1_SB_DQ<13>
  VSS53  = GND
  DQ16_B  = M_D_CPU1_SB_DQ<16>
  VSS54  = GND
  DQ17_B  = M_D_CPU1_SB_DQ<17>
  VSS55  = GND
  DQS2_B_T  = M_D_CPU1_SB_DQS_DP<2>
  DQS2_B_C  = M_D_CPU1_SB_DQS_DN<2>
  VSS56  = GND
  DQ20_B  = M_D_CPU1_SB_DQ<20>
  VSS57  = GND
  DQ21_B  = M_D_CPU1_SB_DQ<21>
  VSS58  = GND
  DQ24_B  = M_D_CPU1_SB_DQ<24>
  VSS59  = GND
  DQ25_B  = M_D_CPU1_SB_DQ<25>
  VSS60  = GND
  DQS3_B_T  = M_D_CPU1_SB_DQS_DP<3>
  DQS3_B_C  = M_D_CPU1_SB_DQS_DN<3>
  VSS61  = GND
  DQ28_B  = M_D_CPU1_SB_DQ<28>
  VSS62  = GND
  DQ29_B  = M_D_CPU1_SB_DQ<29>
  VSS63  = GND
  RFU1  = TP_CHD_CPU1_DIMM1_FRU_1
  VIN_BULK1  = P12V_S3_AUX_CPU1_NVDIMM
  VIN_BULK2  = P12V_S3_AUX_CPU1_NVDIMM
  \pwr_good||fail_n\  = PWRGD_CHD_CPU1_DIMM1
  HSA  = PD_CHD_CPU1_DIMM1_SAA
  RFU2  = TP_CHD_CPU1_DIMM1_FRU_2
  RFU3  = TP_CHD_CPU1_DIMM1_FRU_3
  VSS64  = GND
  DQ2_A  = M_D_CPU1_SA_DQ<2>
  VSS65  = GND
  DQ3_A  = M_D_CPU1_SA_DQ<3>
  VSS66  = GND
  \dqs5_a_c||tdqs5_a_c||dqs5_a_t||tdqs5_a_t\  = M_D_CPU1_SA_DQS_DN<5>
  \dqs5_a_t||tdqs5_a_t\  = M_D_CPU1_SA_DQS_DP<5>
  VSS67  = GND
  DQ6_A  = M_D_CPU1_SA_DQ<6>
  VSS68  = GND
  DQ7_A  = M_D_CPU1_SA_DQ<7>
  VSS69  = GND
  DQ10_A  = M_D_CPU1_SA_DQ<10>
  VSS70  = GND
  DQ11_A  = M_D_CPU1_SA_DQ<11>
  VSS71  = GND
  \dqs6_a_c||tdqs6_a_c||dqs6_a_t||tdqs6_a_t\  = M_D_CPU1_SA_DQS_DN<6>
  \dqs6_a_t||tdqs6_a_t\  = M_D_CPU1_SA_DQS_DP<6>
  VSS72  = GND
  DQ14_A  = M_D_CPU1_SA_DQ<14>
  VSS73  = GND
  DQ15_A  = M_D_CPU1_SA_DQ<15>
  VSS74  = GND
  DQ18_A  = M_D_CPU1_SA_DQ<18>
  VSS75  = GND
  DQ19_A  = M_D_CPU1_SA_DQ<19>
  VSS76  = GND
  \dqs7_a_c||tdqs7_a_c\  = M_D_CPU1_SA_DQS_DN<7>
  \dqs7_a_t||tdqs7_a_t\  = M_D_CPU1_SA_DQS_DP<7>
  VSS77  = GND
  DQ22_A  = M_D_CPU1_SA_DQ<22>
  VSS78  = GND
  DQ23_A  = M_D_CPU1_SA_DQ<23>
  VSS79  = GND
  DQ26_A  = M_D_CPU1_SA_DQ<26>
  VSS80  = GND
  DQ27_A  = M_D_CPU1_SA_DQ<27>
  VSS81  = GND
  \dqs8_a_c||tdqs8_a_c\  = M_D_CPU1_SA_DQS_DN<8>
  \dqs8_a_t||tdqs8_a_t\  = M_D_CPU1_SA_DQS_DP<8>
  VSS82  = GND
  DQ30_A  = M_D_CPU1_SA_DQ<30>
  VSS83  = GND
  DQ31_A  = M_D_CPU1_SA_DQ<31>
  VSS84  = GND
  CB2_A  = M_D_CPU1_SA_CB<2>
  VSS85  = GND
  CB3_A  = M_D_CPU1_SA_CB<3>
  VSS86  = GND
  \dqs9_a_c||tdqs9_a_c\  = M_D_CPU1_SA_DQS_DN<9>
  \dqs9_a_t||tdqs9_a_t\  = M_D_CPU1_SA_DQS_DP<9>
  VSS87  = GND
  CB6_A  = M_D_CPU1_SA_CB<6>
  VSS88  = GND
  CB7_A  = M_D_CPU1_SA_CB<7>
  VSS89  = GND
  RESET_N  = RST_M_CD_CPU1_FPGA_N
  VSS90  = GND
  CS1_A_N  = M_D_CPU1_SA_CS_N<1>
  VSS91  = GND
  CA1_A  = M_D_CPU1_SA_CA<1>
  VSS92  = GND
  CA3_A  = M_D_CPU1_SA_CA<3>
  VSS93  = GND
  CA5_A  = M_D_CPU1_SA_CA<5>
  VSS94  = GND
  CK_T  = M_D_CPU1_CLK_DP<0>
  CK_C  = M_D_CPU1_CLK_DN<0>
  VSS95  = GND
  RFU4  = TP_CHD_CPU1_DIMM1_FRU_4
  CA1_B  = M_D_CPU1_SB_CA<1>
  VSS96  = GND
  CA3_B  = M_D_CPU1_SB_CA<3>
  VSS97  = GND
  CA5_B  = M_D_CPU1_SB_CA<5>
  VSS98  = GND
  PAR_B  = M_D_CPU1_SB_PAR
  VSS99  = GND
  CS1_B_N  = M_D_CPU1_SB_CS_N<1>
  VSS100  = GND
  RFU5  = TP_CHD_CPU1_DIMM1_FRU_5
  RFU6  = TP_CHD_CPU1_DIMM1_FRU_6
  VSS101  = GND
  CB6_B  = M_D_CPU1_SB_CB<6>
  VSS102  = GND
  CB7_B  = M_D_CPU1_SB_CB<7>
  VSS103  = GND
  DQS4_B_C  = M_D_CPU1_SB_DQS_DN<4>
  DQS4_B_T  = M_D_CPU1_SB_DQS_DP<4>
  VSS104  = GND
  CB2_B  = M_D_CPU1_SB_CB<2>
  VSS105  = GND
  CB3_B  = M_D_CPU1_SB_CB<3>
  VSS106  = GND
  DQ2_B  = M_D_CPU1_SB_DQ<2>
  VSS107  = GND
  DQ3_B  = M_D_CPU1_SB_DQ<3>
  VSS108  = GND
  \dqs5_b_c||tdqs5_b_c\  = M_D_CPU1_SB_DQS_DN<5>
  \dqs5_b_t||tdqs5_b_t\  = M_D_CPU1_SB_DQS_DP<5>
  VSS109  = GND
  DQ6_B  = M_D_CPU1_SB_DQ<6>
  VSS110  = GND
  DQ7_B  = M_D_CPU1_SB_DQ<7>
  VSS111  = GND
  DQ10_B  = M_D_CPU1_SB_DQ<10>
  VSS112  = GND
  DQ11_B  = M_D_CPU1_SB_DQ<11>
  VSS113  = GND
  \dqs6_b_c||tdqs6_b_c\  = M_D_CPU1_SB_DQS_DN<6>
  \dqs6_b_t||tdqs6_b_t\  = M_D_CPU1_SB_DQS_DP<6>
  VSS114  = GND
  DQ14_B  = M_D_CPU1_SB_DQ<14>
  VSS115  = GND
  DQ15_B  = M_D_CPU1_SB_DQ<15>
  VSS116  = GND
  DQ18_B  = M_D_CPU1_SB_DQ<18>
  VSS117  = GND
  DQ19_B  = M_D_CPU1_SB_DQ<19>
  VSS118  = GND
  \dqs7_b_c||tdqs7_b_c\  = M_D_CPU1_SB_DQS_DN<7>
  \dqs7_b_t||tdqs7_b_t\  = M_D_CPU1_SB_DQS_DP<7>
  VSS119  = GND
  DQ22_B  = M_D_CPU1_SB_DQ<22>
  VSS120  = GND
  DQ23_B  = M_D_CPU1_SB_DQ<23>
  VSS121  = GND
  DQ26_B  = M_D_CPU1_SB_DQ<26>
  VSS122  = GND
  DQ27_B  = M_D_CPU1_SB_DQ<27>
  VSS123  = GND
  \dqs8_b_c||tdqs8_b_c\  = M_D_CPU1_SB_DQS_DN<8>
  \dqs8_b_t||tdqs8_b_t\  = M_D_CPU1_SB_DQS_DP<8>
  VSS124  = GND
  DQ30_B  = M_D_CPU1_SB_DQ<30>
  VSS125  = GND
  DQ31_B  = M_D_CPU1_SB_DQ<31>
  VSS126  = GND
  G1  = GND
  G2  = GND
  G3  = GND

(kicad_pcb
	(version 20260206)
	(generator "pcbnew")
	(generator_version "10.0")
	(general
		(thickness 1.6)
		(legacy_teardrops no)
	)
	(paper "A4")
	(title_block
		(title "03242023_DA0F0TMBIJ0_F0T_Motherboard_J_brd_V01_OCP.brd")
		(comment 1 "Grand Teton / footprint 3586 of 6105 (J23), pads 46-91 of 291")
	)
	(layers
		(0 "F.Cu" signal "TOP")
		(4 "In1.Cu" signal "GND")
		(6 "In2.Cu" signal "IN1")
		(8 "In3.Cu" signal "GND1")
		(10 "In4.Cu" signal "IN2")
		(12 "In5.Cu" signal "GND2")
		(14 "In6.Cu" signal "IN3")
		(16 "In7.Cu" signal "GND3")
		(18 "In8.Cu" signal "VCC")
		(20 "In9.Cu" signal "VCC1")
		(22 "In10.Cu" signal "GND4")
		(24 "In11.Cu" signal "IN4")
		(26 "In12.Cu" signal "GND5")
		(28 "In13.Cu" signal "IN5")
		(30 "In14.Cu" signal "GND6")
		(32 "In15.Cu" signal "IN6")
		(34 "In16.Cu" signal "GND7")
		(2 "B.Cu" signal "BOTTOM")
		(9 "F.Adhes" user "F.Adhesive")
		(11 "B.Adhes" user "B.Adhesive")
		(13 "F.Paste" user "Package Geometry/Pastemask Top")
		(15 "B.Paste" user "Package Geometry/Pastemask Bottom")
		(5 "F.SilkS" user "Ref Des/Silkscreen Top")
		(7 "B.SilkS" user "Ref Des/Silkscreen Bottom")
		(1 "F.Mask" user "Board Geometry/Soldermask Top")
		(3 "B.Mask" user "Board Geometry/Soldermask Bottom")
		(17 "Dwgs.User" user "User.Drawings")
		(19 "Cmts.User" user "User.Comments")
		(21 "Eco1.User" user "User.Eco1")
		(23 "Eco2.User" user "User.Eco2")
		(25 "Edge.Cuts" user "Board Geometry/Outline")
		(27 "Margin" user)
		(31 "F.CrtYd" user "Package Geometry/Place Bound Top")
		(29 "B.CrtYd" user "Package Geometry/Place Bound Bottom")
		(35 "F.Fab" user "Ref Des/Assembly Top")
		(33 "B.Fab" user "Ref Des/Assembly Bottom")
	)
	(footprint ""
		(layer "F.Cu")
		(at 10.19048 -258.091686)
		(property "Reference" "J23"
			(at -5.69468 -80.480408 0)
			(unlocked yes)
			(layer "F.SilkS")
			(effects
				(font
					(size 0.7874 0.5842)
					(thickness 0.1524)
				)
				(justify left)
			)
		)
		(property "Value" ""
			(at 0 0 0)
			(layer "F.Fab")
			(effects
				(font
					(size 1.27 1.27)
				)
			)
		)
		(duplicate_pad_numbers_are_jumpers no)
		(pad "46" smd rect
			(at -2.050034 -25.07488 270)
			(size 0.519938 1.4986)
			(layers "F.Cu" "F.Mask" "F.Paste")
			(net "GND")
		)
		(pad "47" smd rect
			(at -2.050034 -24.224996 270)
			(size 0.519938 1.4986)
			(layers "F.Cu" "F.Mask" "F.Paste")
			(net "M_D_CPU1_SA_DQ<28>")
		)
		(pad "48" smd rect
			(at -2.050034 -23.375112 270)
			(size 0.519938 1.4986)
			(layers "F.Cu" "F.Mask" "F.Paste")
			(net "GND")
		)
		(pad "49" smd rect
			(at -2.050034 -22.524974 270)
			(size 0.519938 1.4986)
			(layers "F.Cu" "F.Mask" "F.Paste")
			(net "M_D_CPU1_SA_DQ<29>")
		)
		(pad "50" smd rect
			(at -2.050034 -21.67509 270)
			(size 0.519938 1.4986)
			(layers "F.Cu" "F.Mask" "F.Paste")
			(net "GND")
		)
		(pad "51" smd rect
			(at -2.050034 -20.824952 270)
			(size 0.519938 1.4986)
			(layers "F.Cu" "F.Mask" "F.Paste")
			(net "M_D_CPU1_SA_CB<0>")
		)
		(pad "52" smd rect
			(at -2.050034 -19.975068 270)
			(size 0.519938 1.4986)
			(layers "F.Cu" "F.Mask" "F.Paste")
			(net "GND")
		)
		(pad "53" smd rect
			(at -2.050034 -19.12493 270)
			(size 0.519938 1.4986)
			(layers "F.Cu" "F.Mask" "F.Paste")
			(net "M_D_CPU1_SA_CB<1>")
		)
		(pad "54" smd rect
			(at -2.050034 -18.275046 270)
			(size 0.519938 1.4986)
			(layers "F.Cu" "F.Mask" "F.Paste")
			(net "GND")
		)
		(pad "55" smd rect
			(at -2.050034 -17.424908 270)
			(size 0.519938 1.4986)
			(layers "F.Cu" "F.Mask" "F.Paste")
			(net "M_D_CPU1_SA_DQS_DP<4>")
		)
		(pad "56" smd rect
			(at -2.050034 -16.575024 270)
			(size 0.519938 1.4986)
			(layers "F.Cu" "F.Mask" "F.Paste")
			(net "M_D_CPU1_SA_DQS_DN<4>")
		)
		(pad "57" smd rect
			(at -2.050034 -15.724886 270)
			(size 0.519938 1.4986)
			(layers "F.Cu" "F.Mask" "F.Paste")
			(net "GND")
		)
		(pad "58" smd rect
			(at -2.050034 -14.875002 270)
			(size 0.519938 1.4986)
			(layers "F.Cu" "F.Mask" "F.Paste")
			(net "M_D_CPU1_SA_CB<4>")
		)
		(pad "59" smd rect
			(at -2.050034 -14.025118 270)
			(size 0.519938 1.4986)
			(layers "F.Cu" "F.Mask" "F.Paste")
			(net "GND")
		)
		(pad "60" smd rect
			(at -2.050034 -13.17498 270)
			(size 0.519938 1.4986)
			(layers "F.Cu" "F.Mask" "F.Paste")
			(net "M_D_CPU1_SA_CB<5>")
		)
		(pad "61" smd rect
			(at -2.050034 -12.325096 270)
			(size 0.519938 1.4986)
			(layers "F.Cu" "F.Mask" "F.Paste")
			(net "GND")
		)
		(pad "62" smd rect
			(at -2.050034 -11.474958 270)
			(size 0.519938 1.4986)
			(layers "F.Cu" "F.Mask" "F.Paste")
			(net "M_D_CPU1_ALERT_N")
		)
		(pad "63" smd rect
			(at -2.050034 -10.625074 270)
			(size 0.519938 1.4986)
			(layers "F.Cu" "F.Mask" "F.Paste")
			(net "GND")
		)
		(pad "64" smd rect
			(at -2.050034 -9.774936 270)
			(size 0.519938 1.4986)
			(layers "F.Cu" "F.Mask" "F.Paste")
			(net "M_D_CPU1_SA_CS_N<0>")
		)
		(pad "65" smd rect
			(at -2.050034 -8.925052 270)
			(size 0.519938 1.4986)
			(layers "F.Cu" "F.Mask" "F.Paste")
			(net "GND")
		)
		(pad "66" smd rect
			(at -2.050034 -8.074914 270)
			(size 0.519938 1.4986)
			(layers "F.Cu" "F.Mask" "F.Paste")
			(net "M_D_CPU1_SA_CA<0>")
		)
		(pad "67" smd rect
			(at -2.050034 -7.22503 270)
			(size 0.519938 1.4986)
			(layers "F.Cu" "F.Mask" "F.Paste")
			(net "GND")
		)
		(pad "68" smd rect
			(at -2.050034 -6.374892 270)
			(size 0.519938 1.4986)
			(layers "F.Cu" "F.Mask" "F.Paste")
			(net "M_D_CPU1_SA_CA<2>")
		)
		(pad "69" smd rect
			(at -2.050034 -5.525008 270)
			(size 0.519938 1.4986)
			(layers "F.Cu" "F.Mask" "F.Paste")
			(net "GND")
		)
		(pad "70" smd rect
			(at -2.050034 -4.675124 270)
			(size 0.519938 1.4986)
			(layers "F.Cu" "F.Mask" "F.Paste")
			(net "M_D_CPU1_SA_CA<4>")
		)
		(pad "71" smd rect
			(at -2.050034 -3.824986 270)
			(size 0.519938 1.4986)
			(layers "F.Cu" "F.Mask" "F.Paste")
			(net "GND")
		)
		(pad "72" smd rect
			(at -2.050034 -2.975102 270)
			(size 0.519938 1.4986)
			(layers "F.Cu" "F.Mask" "F.Paste")
			(net "M_D_CPU1_SA_CA<6>")
		)
		(pad "73" smd rect
			(at -2.050034 -2.124964 270)
			(size 0.519938 1.4986)
			(layers "F.Cu" "F.Mask" "F.Paste")
			(net "GND")
		)
		(pad "74" smd rect
			(at -2.050034 -1.27508 270)
			(size 0.519938 1.4986)
			(layers "F.Cu" "F.Mask" "F.Paste")
			(net "M_D_CPU1_SA_PAR")
		)
		(pad "75" smd rect
			(at -2.050034 -0.424942 270)
			(size 0.519938 1.4986)
			(layers "F.Cu" "F.Mask" "F.Paste")
			(net "GND")
		)
		(pad "76" smd rect
			(at -2.050034 5.525008 270)
			(size 0.519938 1.4986)
			(layers "F.Cu" "F.Mask" "F.Paste")
			(net "M_D_CPU1_SB_CA<0>")
		)
		(pad "77" smd rect
			(at -2.050034 6.374892 270)
			(size 0.519938 1.4986)
			(layers "F.Cu" "F.Mask" "F.Paste")
			(net "GND")
		)
		(pad "78" smd rect
			(at -2.050034 7.22503 270)
			(size 0.519938 1.4986)
			(layers "F.Cu" "F.Mask" "F.Paste")
			(net "M_D_CPU1_SB_CA<2>")
		)
		(pad "79" smd rect
			(at -2.050034 8.074914 270)
			(size 0.519938 1.4986)
			(layers "F.Cu" "F.Mask" "F.Paste")
			(net "GND")
		)
		(pad "80" smd rect
			(at -2.050034 8.925052 270)
			(size 0.519938 1.4986)
			(layers "F.Cu" "F.Mask" "F.Paste")
			(net "M_D_CPU1_SB_CA<4>")
		)
		(pad "81" smd rect
			(at -2.050034 9.774936 270)
			(size 0.519938 1.4986)
			(layers "F.Cu" "F.Mask" "F.Paste")
			(net "GND")
		)
		(pad "82" smd rect
			(at -2.050034 10.625074 270)
			(size 0.519938 1.4986)
			(layers "F.Cu" "F.Mask" "F.Paste")
			(net "M_D_CPU1_SB_CA<6>")
		)
		(pad "83" smd rect
			(at -2.050034 11.474958 270)
			(size 0.519938 1.4986)
			(layers "F.Cu" "F.Mask" "F.Paste")
			(net "GND")
		)
		(pad "84" smd rect
			(at -2.050034 12.325096 270)
			(size 0.519938 1.4986)
			(layers "F.Cu" "F.Mask" "F.Paste")
			(net "M_D_CPU1_SB_CS_N<0>")
		)
		(pad "85" smd rect
			(at -2.050034 13.17498 270)
			(size 0.519938 1.4986)
			(layers "F.Cu" "F.Mask" "F.Paste")
			(net "GND")
		)
		(pad "86" smd rect
			(at -2.050034 14.025118 270)
			(size 0.519938 1.4986)
			(layers "F.Cu" "F.Mask" "F.Paste")
			(net "M_D_CPU1_SA_RSP<0>")
		)
		(pad "87" smd rect
			(at -2.050034 14.875002 270)
			(size 0.519938 1.4986)
			(layers "F.Cu" "F.Mask" "F.Paste")
			(net "M_D_CPU1_SB_RSP<0>")
		)
		(pad "88" smd rect
			(at -2.050034 15.724886 270)
			(size 0.519938 1.4986)
			(layers "F.Cu" "F.Mask" "F.Paste")
			(net "GND")
		)
		(pad "89" smd rect
			(at -2.050034 16.575024 270)
			(size 0.519938 1.4986)
			(layers "F.Cu" "F.Mask" "F.Paste")
			(net "M_D_CPU1_SB_CB<4>")
		)
		(pad "90" smd rect
			(at -2.050034 17.424908 270)
			(size 0.519938 1.4986)
			(layers "F.Cu" "F.Mask" "F.Paste")
			(net "GND")
		)
		(pad "91" smd rect
			(at -2.050034 18.275046 270)
			(size 0.519938 1.4986)
			(layers "F.Cu" "F.Mask" "F.Paste")
			(net "M_D_CPU1_SB_CB<5>")
		)
	)
)
